# BASEBOARD_FAB2 (Tioga Pass) — schematic netlist excerpt (pin names and nets, part order shuffled) for the footprints in the layout excerpt that follows; sources: Cadence DE-HDL packaged netlist, KiCad conversion of Wiwynn_Tioga_Pass_MB.brd

J1G1  SCONN288_H44441004  SCONN  pkg PIP  page 77
  \12v\(1)  = P12V_NVDIMM_GHJ
  VSS(93)  = GND
  DQ(4)  = M_G_DQ<5>
  VSS(92)  = GND
  DQ(0)  = M_G_DQ<1>
  VSS(91)  = GND
  DQS9P  = M_G_DQS_DP<9>
  DQS9N  = M_G_DQS_DN<9>
  VSS(90)  = GND
  DQ(6)  = M_G_DQ<7>
  VSS(89)  = GND
  DQ(2)  = M_G_DQ<3>
  VSS(88)  = GND
  DQ(12)  = M_G_DQ<13>
  VSS(87)  = GND
  DQ(8)  = M_G_DQ<9>
  VSS(86)  = GND
  DQS10P  = M_G_DQS_DP<10>
  DQS10N  = M_G_DQS_DN<10>
  VSS(85)  = GND
  DQ(14)  = M_G_DQ<15>
  VSS(84)  = GND
  DQ(10)  = M_G_DQ<11>
  VSS(83)  = GND
  DQ(20)  = M_G_DQ<21>
  VSS(82)  = GND
  DQ(16)  = M_G_DQ<17>
  VSS(81)  = GND
  DQS11P  = M_G_DQS_DP<11>
  DQS11N  = M_G_DQS_DN<11>
  VSS(80)  = GND
  DQ(22)  = M_G_DQ<23>
  VSS(79)  = GND
  DQ(18)  = M_G_DQ<19>
  VSS(78)  = GND
  DQ(28)  = M_G_DQ<29>
  VSS(77)  = GND
  DQ(24)  = M_G_DQ<25>
  VSS(76)  = GND
  DQS12P  = M_G_DQS_DP<12>
  DQS12N  = M_G_DQS_DN<12>
  VSS(75)  = GND
  DQ(30)  = M_G_DQ<31>
  VSS(74)  = GND
  DQ(26)  = M_G_DQ<27>
  VSS(73)  = GND
  CB(4)  = M_G_ECC<5>
  VSS(72)  = GND
  CB(0)  = M_G_ECC<1>
  VSS(71)  = GND
  DQS17P  = M_G_DQS_DP<17>
  DQS17N  = M_G_DQS_DN<17>
  VSS(70)  = GND
  CB(6)  = M_G_ECC<7>
  VSS(69)  = GND
  CB(2)  = M_G_ECC<3>
  VSS(68)  = GND
  RESET_N  = M_GHJ_RST_N
  VDD(25)  = PVDDQ_GHJ
  CKE(0)  = M_G_CKE<0>
  VDD(24)  = PVDDQ_GHJ
  ACT_N  = M_G_ACT_N
  BG(0)  = M_G_BG<0>
  VDD(23)  = PVDDQ_GHJ
  A12  = M_G_MA<12>
  A9  = M_G_MA<9>
  VDD(22)  = PVDDQ_GHJ
  A8  = M_G_MA<8>
  A6  = M_G_MA<6>
  VDD(21)  = PVDDQ_GHJ
  A3  = M_G_MA<3>
  A1  = M_G_MA<1>
  VDD(20)  = PVDDQ_GHJ
  CK0P  = M_G_CLK_DP<0>
  CK0N  = M_G_CLK_DN<0>
  VDD(19)  = PVDDQ_GHJ
  VTT(1)  = PVTT_GHJ
  EVENT_N  = FM_DIMM_EVENT_COD_N
  A0  = M_G_MA<0>
  VDD(18)  = PVDDQ_GHJ
  BA(0)  = M_G_BA<0>
  A16_RAS_N  = M_G_MA<16>
  VDD(17)  = PVDDQ_GHJ
  S0_N  = M_G_CS_N<0>
  VDD(16)  = PVDDQ_GHJ
  A15_CAS_N  = M_G_MA<15>
  ODT(0)  = M_G_ODT<0>
  VDD(15)  = PVDDQ_GHJ
  S1_N  = M_G_CS_N<1>
  VDD(14)  = PVDDQ_GHJ
  ODT(1)  = M_G_ODT<1>
  VDD(13)  = PVDDQ_GHJ
  S2_N_C(0)  = M_G_CS_N<2>
  VSS(67)  = GND
  DQ(36)  = M_G_DQ<37>
  VSS(66)  = GND
  DQ(32)  = M_G_DQ<33>
  VSS(65)  = GND
  DQS13P  = M_G_DQS_DP<13>
  DQS13N  = M_G_DQS_DN<13>
  VSS(64)  = GND
  DQ(38)  = M_G_DQ<39>
  VSS(63)  = GND
  DQ(34)  = M_G_DQ<35>
  VSS(62)  = GND
  DQ(44)  = M_G_DQ<45>
  VSS(61)  = GND
  DQ(40)  = M_G_DQ<41>
  VSS(60)  = GND
  DQS14P  = M_G_DQS_DP<14>
  DQS14N  = M_G_DQS_DN<14>
  VSS(59)  = GND
  DQ(46)  = M_G_DQ<47>
  VSS(58)  = GND
  DQ(42)  = M_G_DQ<43>
  VSS(57)  = GND
  DQ(52)  = M_G_DQ<53>
  VSS(56)  = GND
  DQ(48)  = M_G_DQ<49>
  VSS(55)  = GND
  DQS15P  = M_G_DQS_DP<15>
  DQS15N  = M_G_DQS_DN<15>
  VSS(54)  = GND
  DQ(54)  = M_G_DQ<55>
  VSS(53)  = GND
  DQ(50)  = M_G_DQ<51>
  VSS(52)  = GND
  DQ(60)  = M_G_DQ<61>
  VSS(51)  = GND
  DQ(56)  = M_G_DQ<57>
  VSS(50)  = GND
  DQS16P  = M_G_DQS_DP<16>
  DQS16N  = M_G_DQS_DN<16>
  VSS(49)  = GND
  DQ(62)  = M_G_DQ<63>
  VSS(48)  = GND
  DQ(58)  = M_G_DQ<59>
  VSS(47)  = GND
  SA(0)  = GND
  SA(1)  = GND
  SCL  = SMB_DDR_GHJ_VPP_SCL
  VPP(4)  = PVPP_GHJ
  VPP(3)  = PVPP_GHJ
  RFU(2)  = TP_CH_G_DIMM_G0_RFU_2
  \12v\(0)  = P12V_NVDIMM_GHJ
  VREFCA  = M_G_VREF
  VSS(46)  = GND
  DQ(5)  = M_G_DQ<4>
  VSS(45)  = GND
  DQ(1)  = M_G_DQ<0>
  VSS(44)  = GND
  DQS0N  = M_G_DQS_DN<0>
  DQS0P  = M_G_DQS_DP<0>
  VSS(43)  = GND
  DQ(7)  = M_G_DQ<6>
  VSS(42)  = GND
  DQ(3)  = M_G_DQ<2>
  VSS(41)  = GND
  DQ(13)  = M_G_DQ<12>
  VSS(40)  = GND
  DQ(9)  = M_G_DQ<8>
  VSS(39)  = GND
  DQS1N  = M_G_DQS_DN<1>
  DQS1P  = M_G_DQS_DP<1>
  VSS(38)  = GND
  DQ(15)  = M_G_DQ<14>
  VSS(37)  = GND
  DQ(11)  = M_G_DQ<10>
  VSS(36)  = GND
  DQ(21)  = M_G_DQ<20>
  VSS(35)  = GND
  DQ(17)  = M_G_DQ<16>
  VSS(34)  = GND
  DQS2N  = M_G_DQS_DN<2>
  DQS2P  = M_G_DQS_DP<2>
  VSS(33)  = GND
  DQ(23)  = M_G_DQ<22>
  VSS(32)  = GND
  DQ(19)  = M_G_DQ<18>
  VSS(31)  = GND
  DQ(29)  = M_G_DQ<28>
  VSS(30)  = GND
  DQ(25)  = M_G_DQ<24>
  VSS(29)  = GND
  DQS3N  = M_G_DQS_DN<3>
  DQS3P  = M_G_DQS_DP<3>
  VSS(28)  = GND
  DQ(31)  = M_G_DQ<30>
  VSS(27)  = GND
  DQ(27)  = M_G_DQ<26>
  VSS(26)  = GND
  CB(5)  = M_G_ECC<4>
  VSS(25)  = GND
  CB(1)  = M_G_ECC<0>
  VSS(24)  = GND
  DQS8N  = M_G_DQS_DN<8>
  DQS8P  = M_G_DQS_DP<8>
  VSS(23)  = GND
  CB(7)  = M_G_ECC<6>
  VSS(22)  = GND
  CB(3)  = M_G_ECC<2>
  VSS(21)  = GND
  CKE(1)  = M_G_CKE<1>
  VDD(12)  = PVDDQ_GHJ
  RFU(0)  = TP_CH_G_DIMM_G0_RFU_0
  VDD(11)  = PVDDQ_GHJ
  BG(1)  = M_G_BG<1>
  ALERT_N  = M_G_ALERT_N
  VDD(10)  = PVDDQ_GHJ
  A11  = M_G_MA<11>
  A7  = M_G_MA<7>
  VDD(9)  = PVDDQ_GHJ
  A5  = M_G_MA<5>
  A4  = M_G_MA<4>
  VDD(8)  = PVDDQ_GHJ
  A2  = M_G_MA<2>
  VDD(7)  = PVDDQ_GHJ
  CK1P  = M_G_CLK_DP<1>
  CK1N  = M_G_CLK_DN<1>
  VDD(6)  = PVDDQ_GHJ
  VTT(0)  = PVTT_GHJ
  PAR  = M_G_PAR
  VDD(5)  = PVDDQ_GHJ
  BA(1)  = M_G_BA<1>
  A10  = M_G_MA<10>
  VDD(4)  = PVDDQ_GHJ
  RFU(1)  = TP_CH_G_DIMM_G0_RFU_1
  A14_WE_N  = M_G_MA<14>
  VDD(3)  = PVDDQ_GHJ
  SAVE_N_NC  = FM_ADR_COMPLETE_GHJ_N
  VDD(2)  = PVDDQ_GHJ
  A13  = M_G_MA<13>
  VDD(1)  = PVDDQ_GHJ
  A17  = M_G_MA<17>
  C(2)  = M_G_C<2>
  VDD(0)  = PVDDQ_GHJ
  S3_N_C(1)  = M_G_CS_N<3>
  SA(2)  = GND
  VSS(20)  = GND
  DQ(37)  = M_G_DQ<36>
  VSS(19)  = GND
  DQ(33)  = M_G_DQ<32>
  VSS(18)  = GND
  DQS4N  = M_G_DQS_DN<4>
  DQS4P  = M_G_DQS_DP<4>
  VSS(17)  = GND
  DQ(39)  = M_G_DQ<38>
  VSS(16)  = GND
  DQ(35)  = M_G_DQ<34>
  VSS(15)  = GND
  DQ(45)  = M_G_DQ<44>
  VSS(14)  = GND
  DQ(41)  = M_G_DQ<40>
  VSS(13)  = GND
  DQS5N  = M_G_DQS_DN<5>
  DQS5P  = M_G_DQS_DP<5>
  VSS(12)  = GND
  DQ(47)  = M_G_DQ<46>
  VSS(11)  = GND
  DQ(43)  = M_G_DQ<42>
  VSS(10)  = GND
  DQ(53)  = M_G_DQ<52>
  VSS(9)  = GND
  DQ(49)  = M_G_DQ<48>
  VSS(8)  = GND
  DQS6N  = M_G_DQS_DN<6>
  DQS6P  = M_G_DQS_DP<6>
  VSS(7)  = GND
  DQ(55)  = M_G_DQ<54>
  VSS(6)  = GND
  DQ(51)  = M_G_DQ<50>
  VSS(5)  = GND
  DQ(61)  = M_G_DQ<60>
  VSS(4)  = GND
  DQ(57)  = M_G_DQ<56>
  VSS(3)  = GND
  DQS7N  = M_G_DQS_DN<7>
  DQS7P  = M_G_DQS_DP<7>
  VSS(2)  = GND
  DQ(63)  = M_G_DQ<62>
  VSS(1)  = GND
  DQ(59)  = M_G_DQ<58>
  VSS(0)  = GND
  VDDSPD  = PVPP_GHJ
  SDA  = SMB_DDR_GHJ_VPP_SDA
  VPP(1)  = PVPP_GHJ
  VPP(0)  = PVPP_GHJ
  VPP(2)  = PVPP_GHJ

(kicad_pcb
	(version 20260206)
	(generator "pcbnew")
	(generator_version "10.0")
	(general
		(thickness 1.6)
		(legacy_teardrops no)
	)
	(paper "A4")
	(title_block
		(title "Wiwynn_Tioga_Pass_MB.brd")
		(comment 1 "Tioga Pass / footprint 2018 of 4770 (J1G1), pads 51-100 of 291")
	)
	(layers
		(0 "F.Cu" signal "TOP")
		(4 "In1.Cu" signal "L2GND")
		(6 "In2.Cu" signal "L3")
		(8 "In3.Cu" signal "L4GND")
		(10 "In4.Cu" signal "L5")
		(12 "In5.Cu" signal "L6GND")
		(14 "In6.Cu" signal "L7VCC")
		(16 "In7.Cu" signal "L8VCC")
		(18 "In8.Cu" signal "L9GND")
		(20 "In9.Cu" signal "L10")
		(22 "In10.Cu" signal "L11GND")
		(24 "In11.Cu" signal "L12")
		(26 "In12.Cu" signal "L13GND")
		(2 "B.Cu" signal "BOTTOM")
		(9 "F.Adhes" user "F.Adhesive")
		(11 "B.Adhes" user "B.Adhesive")
		(13 "F.Paste" user "Package Geometry/Pastemask Top")
		(15 "B.Paste" user "Package Geometry/Pastemask Bottom")
		(5 "F.SilkS" user "Ref Des/Silkscreen Top")
		(7 "B.SilkS" user "Ref Des/Silkscreen Bottom")
		(1 "F.Mask" user "Board Geometry/Soldermask Top")
		(3 "B.Mask" user "Board Geometry/Soldermask Bottom")
		(17 "Dwgs.User" user "User.Drawings")
		(19 "Cmts.User" user "User.Comments")
		(21 "Eco1.User" user "User.Eco1")
		(23 "Eco2.User" user "User.Eco2")
		(25 "Edge.Cuts" user "Board Geometry/Outline")
		(27 "Margin" user)
		(31 "F.CrtYd" user "Package Geometry/Place Bound Top")
		(29 "B.CrtYd" user "Package Geometry/Place Bound Bottom")
		(35 "F.Fab" user "Ref Des/Assembly Top")
		(33 "B.Fab" user "Ref Des/Assembly Bottom")
	)
	(footprint ""
		(layer "F.Cu")
		(at 29.699458 -15.423642 90)
		(property "Reference" "J1G1"
			(at 9.314688 35.070542 0)
			(unlocked yes)
			(layer "F.SilkS")
			(effects
				(font
					(size 0.7874 0.5842)
					(thickness 0.1524)
				)
				(justify left)
			)
		)
		(property "Value" ""
			(at 0 0 90)
			(layer "F.Fab")
			(effects
				(font
					(size 1.27 1.27)
				)
			)
		)
		(duplicate_pad_numbers_are_jumpers no)
		(pad "48" smd rect
			(at 0 39.949882 90)
			(size 1.8034 0.508)
			(layers "F.Cu" "F.Mask" "F.Paste")
			(net "GND")
		)
		(pad "49" smd rect
			(at 0 40.80002 90)
			(size 1.8034 0.508)
			(layers "F.Cu" "F.Mask" "F.Paste")
			(net "M_G_ECC<1>")
		)
		(pad "50" smd rect
			(at 0 41.649904 90)
			(size 1.8034 0.508)
			(layers "F.Cu" "F.Mask" "F.Paste")
			(net "GND")
		)
		(pad "51" smd rect
			(at 0 42.500042 90)
			(size 1.8034 0.508)
			(layers "F.Cu" "F.Mask" "F.Paste")
			(net "M_G_DQS_DP<17>")
		)
		(pad "52" smd rect
			(at 0 43.349926 90)
			(size 1.8034 0.508)
			(layers "F.Cu" "F.Mask" "F.Paste")
			(net "M_G_DQS_DN<17>")
		)
		(pad "53" smd rect
			(at 0 44.200064 90)
			(size 1.8034 0.508)
			(layers "F.Cu" "F.Mask" "F.Paste")
			(net "GND")
		)
		(pad "54" smd rect
			(at 0 45.049948 90)
			(size 1.8034 0.508)
			(layers "F.Cu" "F.Mask" "F.Paste")
			(net "M_G_ECC<7>")
		)
		(pad "55" smd rect
			(at 0 45.900086 90)
			(size 1.8034 0.508)
			(layers "F.Cu" "F.Mask" "F.Paste")
			(net "GND")
		)
		(pad "56" smd rect
			(at 0 46.74997 90)
			(size 1.8034 0.508)
			(layers "F.Cu" "F.Mask" "F.Paste")
			(net "M_G_ECC<3>")
		)
		(pad "57" smd rect
			(at 0 47.600108 90)
			(size 1.8034 0.508)
			(layers "F.Cu" "F.Mask" "F.Paste")
			(net "GND")
		)
		(pad "58" smd rect
			(at 0 48.449992 90)
			(size 1.8034 0.508)
			(layers "F.Cu" "F.Mask" "F.Paste")
			(net "M_GHJ_RST_N")
		)
		(pad "59" smd rect
			(at 0 49.299876 90)
			(size 1.8034 0.508)
			(layers "F.Cu" "F.Mask" "F.Paste")
			(net "PVDDQ_GHJ")
		)
		(pad "60" smd rect
			(at 0 50.150014 90)
			(size 1.8034 0.508)
			(layers "F.Cu" "F.Mask" "F.Paste")
			(net "M_G_CKE<0>")
		)
		(pad "61" smd rect
			(at 0 50.999898 90)
			(size 1.8034 0.508)
			(layers "F.Cu" "F.Mask" "F.Paste")
			(net "PVDDQ_GHJ")
		)
		(pad "62" smd rect
			(at 0 51.850036 90)
			(size 1.8034 0.508)
			(layers "F.Cu" "F.Mask" "F.Paste")
			(net "M_G_ACT_N")
		)
		(pad "63" smd rect
			(at 0 52.69992 90)
			(size 1.8034 0.508)
			(layers "F.Cu" "F.Mask" "F.Paste")
			(net "M_G_BG<0>")
		)
		(pad "64" smd rect
			(at 0 53.550058 90)
			(size 1.8034 0.508)
			(layers "F.Cu" "F.Mask" "F.Paste")
			(net "PVDDQ_GHJ")
		)
		(pad "65" smd rect
			(at 0 54.399942 90)
			(size 1.8034 0.508)
			(layers "F.Cu" "F.Mask" "F.Paste")
			(net "M_G_MA<12>")
		)
		(pad "66" smd rect
			(at 0 55.25008 90)
			(size 1.8034 0.508)
			(layers "F.Cu" "F.Mask" "F.Paste")
			(net "M_G_MA<9>")
		)
		(pad "67" smd rect
			(at 0 56.099964 90)
			(size 1.8034 0.508)
			(layers "F.Cu" "F.Mask" "F.Paste")
			(net "PVDDQ_GHJ")
		)
		(pad "68" smd rect
			(at 0 56.950102 90)
			(size 1.8034 0.508)
			(layers "F.Cu" "F.Mask" "F.Paste")
			(net "M_G_MA<8>")
		)
		(pad "69" smd rect
			(at 0 57.799986 90)
			(size 1.8034 0.508)
			(layers "F.Cu" "F.Mask" "F.Paste")
			(net "M_G_MA<6>")
		)
		(pad "70" smd rect
			(at 0 58.650124 90)
			(size 1.8034 0.508)
			(layers "F.Cu" "F.Mask" "F.Paste")
			(net "PVDDQ_GHJ")
		)
		(pad "71" smd rect
			(at 0 59.500008 90)
			(size 1.8034 0.508)
			(layers "F.Cu" "F.Mask" "F.Paste")
			(net "M_G_MA<3>")
		)
		(pad "72" smd rect
			(at 0 60.349892 90)
			(size 1.8034 0.508)
			(layers "F.Cu" "F.Mask" "F.Paste")
			(net "M_G_MA<1>")
		)
		(pad "73" smd rect
			(at 0 61.20003 90)
			(size 1.8034 0.508)
			(layers "F.Cu" "F.Mask" "F.Paste")
			(net "PVDDQ_GHJ")
		)
		(pad "74" smd rect
			(at 0 62.049914 90)
			(size 1.8034 0.508)
			(layers "F.Cu" "F.Mask" "F.Paste")
			(net "M_G_CLK_DP<0>")
		)
		(pad "75" smd rect
			(at 0 62.900052 90)
			(size 1.8034 0.508)
			(layers "F.Cu" "F.Mask" "F.Paste")
			(net "M_G_CLK_DN<0>")
		)
		(pad "76" smd rect
			(at 0 63.749936 90)
			(size 1.8034 0.508)
			(layers "F.Cu" "F.Mask" "F.Paste")
			(net "PVDDQ_GHJ")
		)
		(pad "77" smd rect
			(at 0 64.600074 90)
			(size 1.8034 0.508)
			(layers "F.Cu" "F.Mask" "F.Paste")
			(net "PVTT_GHJ")
		)
		(pad "78" smd rect
			(at 0 70.550024 90)
			(size 1.8034 0.508)
			(layers "F.Cu" "F.Mask" "F.Paste")
			(net "FM_DIMM_EVENT_COD_N")
		)
		(pad "79" smd rect
			(at 0 71.399908 90)
			(size 1.8034 0.508)
			(layers "F.Cu" "F.Mask" "F.Paste")
			(net "M_G_MA<0>")
		)
		(pad "80" smd rect
			(at 0 72.250046 90)
			(size 1.8034 0.508)
			(layers "F.Cu" "F.Mask" "F.Paste")
			(net "PVDDQ_GHJ")
		)
		(pad "81" smd rect
			(at 0 73.09993 90)
			(size 1.8034 0.508)
			(layers "F.Cu" "F.Mask" "F.Paste")
			(net "M_G_BA<0>")
		)
		(pad "82" smd rect
			(at 0 73.950068 90)
			(size 1.8034 0.508)
			(layers "F.Cu" "F.Mask" "F.Paste")
			(net "M_G_MA<16>")
		)
		(pad "83" smd rect
			(at 0 74.799952 90)
			(size 1.8034 0.508)
			(layers "F.Cu" "F.Mask" "F.Paste")
			(net "PVDDQ_GHJ")
		)
		(pad "84" smd rect
			(at 0 75.65009 90)
			(size 1.8034 0.508)
			(layers "F.Cu" "F.Mask" "F.Paste")
			(net "M_G_CS_N<0>")
		)
		(pad "85" smd rect
			(at 0 76.499974 90)
			(size 1.8034 0.508)
			(layers "F.Cu" "F.Mask" "F.Paste")
			(net "PVDDQ_GHJ")
		)
		(pad "86" smd rect
			(at 0 77.350112 90)
			(size 1.8034 0.508)
			(layers "F.Cu" "F.Mask" "F.Paste")
			(net "M_G_MA<15>")
		)
		(pad "87" smd rect
			(at 0 78.199996 90)
			(size 1.8034 0.508)
			(layers "F.Cu" "F.Mask" "F.Paste")
			(net "M_G_ODT<0>")
		)
		(pad "88" smd rect
			(at 0 79.04988 90)
			(size 1.8034 0.508)
			(layers "F.Cu" "F.Mask" "F.Paste")
			(net "PVDDQ_GHJ")
		)
		(pad "89" smd rect
			(at 0 79.900018 90)
			(size 1.8034 0.508)
			(layers "F.Cu" "F.Mask" "F.Paste")
			(net "M_G_CS_N<1>")
		)
		(pad "90" smd rect
			(at 0 80.749902 90)
			(size 1.8034 0.508)
			(layers "F.Cu" "F.Mask" "F.Paste")
			(net "PVDDQ_GHJ")
		)
		(pad "91" smd rect
			(at 0 81.60004 90)
			(size 1.8034 0.508)
			(layers "F.Cu" "F.Mask" "F.Paste")
			(net "M_G_ODT<1>")
		)
		(pad "92" smd rect
			(at 0 82.449924 90)
			(size 1.8034 0.508)
			(layers "F.Cu" "F.Mask" "F.Paste")
			(net "PVDDQ_GHJ")
		)
		(pad "93" smd rect
			(at 0 83.300062 90)
			(size 1.8034 0.508)
			(layers "F.Cu" "F.Mask" "F.Paste")
			(net "M_G_CS_N<2>")
		)
		(pad "94" smd rect
			(at 0 84.149946 90)
			(size 1.8034 0.508)
			(layers "F.Cu" "F.Mask" "F.Paste")
			(net "GND")
		)
		(pad "95" smd rect
			(at 0 85.000084 90)
			(size 1.8034 0.508)
			(layers "F.Cu" "F.Mask" "F.Paste")
			(net "M_G_DQ<37>")
		)
		(pad "96" smd rect
			(at 0 85.849968 90)
			(size 1.8034 0.508)
			(layers "F.Cu" "F.Mask" "F.Paste")
			(net "GND")
		)
		(pad "97" smd rect
			(at 0 86.700106 90)
			(size 1.8034 0.508)
			(layers "F.Cu" "F.Mask" "F.Paste")
			(net "M_G_DQ<33>")
		)
	)
)
